(kicad_pcb
	(version 20260206)
	(generator "pcbnew")
	(generator_version "10.0")
	(general
		(thickness 1.6)
		(legacy_teardrops no)
	)
	(paper "A4")
	(title_block
		(title "Bryce Canyon_R.DPB_16317-1_OCP.brd")
		(comment 1 "Bryce Canyon / footprints 674-680 of 2099")
	)
	(layers
		(0 "F.Cu" signal "TOP")
		(4 "In1.Cu" signal "L2GND")
		(6 "In2.Cu" signal "L3")
		(8 "In3.Cu" signal "L4VCC")
		(10 "In4.Cu" signal "L5VCC")
		(12 "In5.Cu" signal "L6")
		(14 "In6.Cu" signal "L7GND")
		(2 "B.Cu" signal "BOTTOM")
		(9 "F.Adhes" user "F.Adhesive")
		(11 "B.Adhes" user "B.Adhesive")
		(13 "F.Paste" user "Package Geometry/Pastemask Top")
		(15 "B.Paste" user "Package Geometry/Pastemask Bottom")
		(5 "F.SilkS" user "Ref Des/Silkscreen Top")
		(7 "B.SilkS" user "Ref Des/Silkscreen Bottom")
		(1 "F.Mask" user "Board Geometry/Soldermask Top")
		(3 "B.Mask" user "Board Geometry/Soldermask Bottom")
		(17 "Dwgs.User" user "User.Drawings")
		(19 "Cmts.User" user "User.Comments")
		(21 "Eco1.User" user "User.Eco1")
		(23 "Eco2.User" user "User.Eco2")
		(25 "Edge.Cuts" user "Board Geometry/Outline")
		(27 "Margin" user)
		(31 "F.CrtYd" user "Package Geometry/Place Bound Top")
		(29 "B.CrtYd" user "Package Geometry/Place Bound Bottom")
		(35 "F.Fab" user "Ref Des/Assembly Top")
		(33 "B.Fab" user "Ref Des/Assembly Bottom")
	)
	(footprint ""
		(layer "F.Cu")
		(at 141.097 -246.634 90)
		(property "Reference" "R232"
			(at 0 0 90)
			(layer "F.SilkS")
			(hide yes)
			(effects
				(font
					(size 1.27 1.27)
				)
			)
		)
		(property "Value" "4K7R2J-2-GP"
			(at 0.064008 -3.993896 90)
			(unlocked yes)
			(layer "F.Fab")
			(hide yes)
			(effects
				(font
					(size 1.016 1.016)
					(thickness 0.1524)
				)
			)
		)
		(property "Device Type" "R402H16"
			(at 0.064008 -5.517896 90)
			(unlocked yes)
			(layer "F.Fab")
			(hide yes)
			(effects
				(font
					(size 1.016 1.016)
					(thickness 0.1524)
				)
			)
		)
		(duplicate_pad_numbers_are_jumpers no)
		(fp_line
			(start 0.508 -0.9398)
			(end -0.508 -0.9398)
			(stroke
				(width 0.1524)
				(type default)
			)
			(layer "F.SilkS")
		)
		(fp_line
			(start -0.508 -0.9398)
			(end -0.508 0.9398)
			(stroke
				(width 0.1524)
				(type default)
			)
			(layer "F.SilkS")
		)
		(fp_rect
			(start -0.508 0.9398)
			(end 0.508 -0.9398)
			(stroke
				(width 0)
				(type default)
			)
			(fill no)
			(layer "F.CrtYd")
		)
		(fp_rect
			(start -0.508 0.9398)
			(end 0.508 -0.9398)
			(stroke
				(width 0)
				(type default)
			)
			(fill no)
			(layer "F.Fab")
		)
		(pad "1" smd custom
			(at 0 -0.4445 90)
			(size 0.1397 0.1397)
			(layers "F.Cu" "F.Mask" "F.Paste")
			(net "P12V_B")
			(options
				(clearance outline)
				(anchor circle)
			)
			(primitives
				(gr_poly
					(pts
						(arc
							(start -0.1778 -0.2794)
							(mid -0.249642 -0.249642)
							(end -0.2794 -0.1778)
						)
						(arc
							(start -0.2794 0.1778)
							(mid -0.249642 0.249642)
							(end -0.1778 0.2794)
						)
						(arc
							(start 0.1778 0.2794)
							(mid 0.249642 0.249642)
							(end 0.2794 0.1778)
						)
						(arc
							(start 0.2794 -0.1778)
							(mid 0.249642 -0.249642)
							(end 0.1778 -0.2794)
						)
					)
					(width 0)
					(fill yes)
				)
			)
		)
		(pad "2" smd custom
			(at 0 0.4445 90)
			(size 0.1397 0.1397)
			(layers "F.Cu" "F.Mask" "F.Paste")
			(net "SW_HDD_R4")
			(options
				(clearance outline)
				(anchor circle)
			)
			(primitives
				(gr_poly
					(pts
						(arc
							(start -0.1778 -0.2794)
							(mid -0.249642 -0.249642)
							(end -0.2794 -0.1778)
						)
						(arc
							(start -0.2794 0.1778)
							(mid -0.249642 0.249642)
							(end -0.1778 0.2794)
						)
						(arc
							(start 0.1778 0.2794)
							(mid 0.249642 0.249642)
							(end 0.2794 0.1778)
						)
						(arc
							(start 0.2794 -0.1778)
							(mid 0.249642 -0.249642)
							(end 0.1778 -0.2794)
						)
					)
					(width 0)
					(fill yes)
				)
			)
		)
	)
	(footprint ""
		(layer "F.Cu")
		(at 209.775298 -223.585024 -90)
		(property "Reference" "R25"
			(at 0 0 270)
			(layer "F.SilkS")
			(hide yes)
			(effects
				(font
					(size 1.27 1.27)
				)
			)
		)
		(property "Value" "4K7R2F-GP"
			(at 0.064008 -3.993896 270)
			(unlocked yes)
			(layer "F.Fab")
			(hide yes)
			(effects
				(font
					(size 1.016 1.016)
					(thickness 0.1524)
				)
			)
		)
		(property "Device Type" "R402H16"
			(at 0.064008 -5.517896 270)
			(unlocked yes)
			(layer "F.Fab")
			(hide yes)
			(effects
				(font
					(size 1.016 1.016)
					(thickness 0.1524)
				)
			)
		)
		(duplicate_pad_numbers_are_jumpers no)
		(fp_line
			(start -0.508 -0.9398)
			(end -0.508 0.9398)
			(stroke
				(width 0.1524)
				(type default)
			)
			(layer "F.SilkS")
		)
		(fp_line
			(start 0.508 -0.9398)
			(end -0.508 -0.9398)
			(stroke
				(width 0.1524)
				(type default)
			)
			(layer "F.SilkS")
		)
		(fp_rect
			(start -0.508 0.9398)
			(end 0.508 -0.9398)
			(stroke
				(width 0)
				(type default)
			)
			(fill no)
			(layer "F.CrtYd")
		)
		(fp_rect
			(start -0.508 0.9398)
			(end 0.508 -0.9398)
			(stroke
				(width 0)
				(type default)
			)
			(fill no)
			(layer "F.Fab")
		)
		(pad "1" smd custom
			(at 0 -0.4445 270)
			(size 0.1397 0.1397)
			(layers "F.Cu" "F.Mask" "F.Paste")
			(net "IO_EXP1_HDD_FAULT_A2")
			(options
				(clearance outline)
				(anchor circle)
			)
			(primitives
				(gr_poly
					(pts
						(arc
							(start -0.1778 -0.2794)
							(mid -0.249642 -0.249642)
							(end -0.2794 -0.1778)
						)
						(arc
							(start -0.2794 0.1778)
							(mid -0.249642 0.249642)
							(end -0.1778 0.2794)
						)
						(arc
							(start 0.1778 0.2794)
							(mid 0.249642 0.249642)
							(end 0.2794 0.1778)
						)
						(arc
							(start 0.2794 -0.1778)
							(mid 0.249642 -0.249642)
							(end 0.1778 -0.2794)
						)
					)
					(width 0)
					(fill yes)
				)
			)
		)
		(pad "2" smd custom
			(at 0 0.4445 270)
			(size 0.1397 0.1397)
			(layers "F.Cu" "F.Mask" "F.Paste")
			(net "GND")
			(options
				(clearance outline)
				(anchor circle)
			)
			(primitives
				(gr_poly
					(pts
						(arc
							(start -0.1778 -0.2794)
							(mid -0.249642 -0.249642)
							(end -0.2794 -0.1778)
						)
						(arc
							(start -0.2794 0.1778)
							(mid -0.249642 0.249642)
							(end -0.1778 0.2794)
						)
						(arc
							(start 0.1778 0.2794)
							(mid 0.249642 0.249642)
							(end 0.2794 0.1778)
						)
						(arc
							(start 0.2794 -0.1778)
							(mid 0.249642 -0.249642)
							(end 0.1778 -0.2794)
						)
					)
					(width 0)
					(fill yes)
				)
			)
		)
	)
	(footprint ""
		(layer "F.Cu")
		(at 463.2706 -25.6032 90)
		(property "Reference" "R868"
			(at 0 0 90)
			(layer "F.SilkS")
			(hide yes)
			(effects
				(font
					(size 1.27 1.27)
				)
			)
		)
		(property "Value" "200KR2F-L-GP"
			(at 0.064008 -3.993896 90)
			(unlocked yes)
			(layer "F.Fab")
			(hide yes)
			(effects
				(font
					(size 1.016 1.016)
					(thickness 0.1524)
				)
			)
		)
		(property "Device Type" "R402H16"
			(at 0.064008 -5.517896 90)
			(unlocked yes)
			(layer "F.Fab")
			(hide yes)
			(effects
				(font
					(size 1.016 1.016)
					(thickness 0.1524)
				)
			)
		)
		(duplicate_pad_numbers_are_jumpers no)
		(fp_line
			(start 0.508 -0.9398)
			(end -0.508 -0.9398)
			(stroke
				(width 0.1524)
				(type default)
			)
			(layer "F.SilkS")
		)
		(fp_line
			(start -0.508 -0.9398)
			(end -0.508 0.9398)
			(stroke
				(width 0.1524)
				(type default)
			)
			(layer "F.SilkS")
		)
		(fp_rect
			(start -0.508 0.9398)
			(end 0.508 -0.9398)
			(stroke
				(width 0)
				(type default)
			)
			(fill no)
			(layer "F.CrtYd")
		)
		(fp_rect
			(start -0.508 0.9398)
			(end 0.508 -0.9398)
			(stroke
				(width 0)
				(type default)
			)
			(fill no)
			(layer "F.Fab")
		)
		(pad "1" smd custom
			(at 0 -0.4445 90)
			(size 0.1397 0.1397)
			(layers "F.Cu" "F.Mask" "F.Paste")
			(net "SW_HDD_R34")
			(options
				(clearance outline)
				(anchor circle)
			)
			(primitives
				(gr_poly
					(pts
						(arc
							(start -0.1778 -0.2794)
							(mid -0.249642 -0.249642)
							(end -0.2794 -0.1778)
						)
						(arc
							(start -0.2794 0.1778)
							(mid -0.249642 0.249642)
							(end -0.1778 0.2794)
						)
						(arc
							(start 0.1778 0.2794)
							(mid 0.249642 0.249642)
							(end 0.2794 0.1778)
						)
						(arc
							(start 0.2794 -0.1778)
							(mid 0.249642 -0.249642)
							(end 0.1778 -0.2794)
						)
					)
					(width 0)
					(fill yes)
				)
			)
		)
		(pad "2" smd custom
			(at 0 0.4445 90)
			(size 0.1397 0.1397)
			(layers "F.Cu" "F.Mask" "F.Paste")
			(net "SW_HDD_N34")
			(options
				(clearance outline)
				(anchor circle)
			)
			(primitives
				(gr_poly
					(pts
						(arc
							(start -0.1778 -0.2794)
							(mid -0.249642 -0.249642)
							(end -0.2794 -0.1778)
						)
						(arc
							(start -0.2794 0.1778)
							(mid -0.249642 0.249642)
							(end -0.1778 0.2794)
						)
						(arc
							(start 0.1778 0.2794)
							(mid 0.249642 0.249642)
							(end 0.2794 0.1778)
						)
						(arc
							(start 0.2794 -0.1778)
							(mid 0.249642 -0.249642)
							(end 0.1778 -0.2794)
						)
					)
					(width 0)
					(fill yes)
				)
			)
		)
	)
	(footprint ""
		(layer "F.Cu")
		(at 457.499974 -7.999984 180)
		(property "Reference" "U16"
			(at 0 0 180)
			(layer "F.SilkS")
			(hide yes)
			(effects
				(font
					(size 1.27 1.27)
				)
			)
		)
		(property "Value" "TMP75AIDGKR-GP"
			(at -0.1143 -9.1948 180)
			(unlocked yes)
			(layer "F.Fab")
			(hide yes)
			(effects
				(font
					(size 1.016 1.016)
					(thickness 0.1524)
				)
			)
		)
		(property "Device Type" "MSOP8-1H44"
			(at -0.1143 -10.795 180)
			(unlocked yes)
			(layer "F.Fab")
			(hide yes)
			(effects
				(font
					(size 1.016 1.016)
					(thickness 0.1524)
				)
			)
		)
		(duplicate_pad_numbers_are_jumpers no)
		(fp_line
			(start 1.0795 1.016)
			(end 1.0795 -1.016)
			(stroke
				(width 0.1524)
				(type default)
			)
			(layer "F.SilkS")
		)
		(fp_line
			(start 1.0795 -1.016)
			(end -1.9558 -1.016)
			(stroke
				(width 0.1524)
				(type default)
			)
			(layer "F.SilkS")
		)
		(fp_line
			(start -1.4478 -0.0381)
			(end -1.9558 0.4699)
			(stroke
				(width 0.1524)
				(type default)
			)
			(layer "F.SilkS")
		)
		(fp_line
			(start -1.778 1.0922)
			(end -1.778 3.048)
			(stroke
				(width 0.508)
				(type default)
			)
			(layer "F.SilkS")
		)
		(fp_line
			(start -1.9558 1.016)
			(end 1.0795 1.016)
			(stroke
				(width 0.1524)
				(type default)
			)
			(layer "F.SilkS")
		)
		(fp_line
			(start -1.9558 -0.5461)
			(end -1.4478 -0.0381)
			(stroke
				(width 0.1524)
				(type default)
			)
			(layer "F.SilkS")
		)
		(fp_line
			(start -1.9558 -1.016)
			(end -1.9558 1.016)
			(stroke
				(width 0.1524)
				(type default)
			)
			(layer "F.SilkS")
		)
		(fp_poly
			(pts
				(xy -1.1557 -1.016) (xy -1.1557 1.016) (xy 1.1557 1.016) (xy 1.1557 -1.016)
			)
			(stroke
				(width 0)
				(type default)
			)
			(fill yes)
			(layer "F.SilkS")
		)
		(fp_rect
			(start -1.4986 2.4511)
			(end 1.4986 -2.4511)
			(stroke
				(width 0)
				(type default)
			)
			(fill no)
			(layer "F.CrtYd")
		)
		(fp_poly
			(pts
				(xy -2.032 3.302) (xy -2.032 -3.302) (xy 2.032 -3.302) (xy 2.032 -2.1209) (xy 1.4986 -2.1209) (xy 1.4986 -2.4511)
				(xy -1.4986 -2.4511) (xy -1.4986 2.4511) (xy 1.4986 2.4511) (xy 1.4986 -2.1082) (xy 2.032 -2.1082)
				(xy 2.032 3.302)
			)
			(stroke
				(width 0)
				(type default)
			)
			(fill no)
			(layer "F.CrtYd")
		)
		(fp_rect
			(start -2.032 3.302)
			(end 2.032 -3.302)
			(stroke
				(width 0)
				(type default)
			)
			(fill no)
			(layer "F.Fab")
		)
		(pad "1" smd rect
			(at -0.97536 2.05486 180)
			(size 0.3556 1.524)
			(layers "F.Cu" "F.Mask" "F.Paste")
			(net "TEMP2_SDA")
		)
		(pad "2" smd rect
			(at -0.32512 2.05486 180)
			(size 0.3556 1.524)
			(layers "F.Cu" "F.Mask" "F.Paste")
			(net "TEMP2_SCL")
		)
		(pad "3" smd rect
			(at 0.32512 2.05486 180)
			(size 0.3556 1.524)
			(layers "F.Cu" "F.Mask" "F.Paste")
			(net "TEMP2_ALERT")
		)
		(pad "4" smd rect
			(at 0.97536 2.05486 180)
			(size 0.3556 1.524)
			(layers "F.Cu" "F.Mask" "F.Paste")
			(net "GND")
		)
		(pad "5" smd rect
			(at 0.97536 -2.05486 180)
			(size 0.3556 1.524)
			(layers "F.Cu" "F.Mask" "F.Paste")
			(net "TEMP2_A2")
		)
		(pad "6" smd rect
			(at 0.32512 -2.05486 180)
			(size 0.3556 1.524)
			(layers "F.Cu" "F.Mask" "F.Paste")
			(net "TEMP2_A1")
		)
		(pad "7" smd rect
			(at -0.32512 -2.05486 180)
			(size 0.3556 1.524)
			(layers "F.Cu" "F.Mask" "F.Paste")
			(net "TEMP2_A0")
		)
		(pad "8" smd rect
			(at -0.97536 -2.05486 180)
			(size 0.3556 1.524)
			(layers "F.Cu" "F.Mask" "F.Paste")
			(net "P3V3_STBY_B")
		)
	)
	(footprint ""
		(layer "F.Cu")
		(at 268.224 -206.883 90)
		(property "Reference" "R12"
			(at 0 0 90)
			(layer "F.SilkS")
			(hide yes)
			(effects
				(font
					(size 1.27 1.27)
				)
			)
		)
		(property "Value" "1KR2J-1-GP"
			(at 0.064008 -3.993896 90)
			(unlocked yes)
			(layer "F.Fab")
			(hide yes)
			(effects
				(font
					(size 1.016 1.016)
					(thickness 0.1524)
				)
			)
		)
		(property "Device Type" "R402H16"
			(at 0.064008 -5.517896 90)
			(unlocked yes)
			(layer "F.Fab")
			(hide yes)
			(effects
				(font
					(size 1.016 1.016)
					(thickness 0.1524)
				)
			)
		)
		(duplicate_pad_numbers_are_jumpers no)
		(fp_line
			(start 0.508 -0.9398)
			(end -0.508 -0.9398)
			(stroke
				(width 0.1524)
				(type default)
			)
			(layer "F.SilkS")
		)
		(fp_line
			(start -0.508 -0.9398)
			(end -0.508 0.9398)
			(stroke
				(width 0.1524)
				(type default)
			)
			(layer "F.SilkS")
		)
		(fp_rect
			(start -0.508 0.9398)
			(end 0.508 -0.9398)
			(stroke
				(width 0)
				(type default)
			)
			(fill no)
			(layer "F.CrtYd")
		)
		(fp_rect
			(start -0.508 0.9398)
			(end 0.508 -0.9398)
			(stroke
				(width 0)
				(type default)
			)
			(fill no)
			(layer "F.Fab")
		)
		(pad "1" smd custom
			(at 0 -0.4445 90)
			(size 0.1397 0.1397)
			(layers "F.Cu" "F.Mask" "F.Paste")
			(net "P3V3_STBY_B")
			(options
				(clearance outline)
				(anchor circle)
			)
			(primitives
				(gr_poly
					(pts
						(arc
							(start -0.1778 -0.2794)
							(mid -0.249642 -0.249642)
							(end -0.2794 -0.1778)
						)
						(arc
							(start -0.2794 0.1778)
							(mid -0.249642 0.249642)
							(end -0.1778 0.2794)
						)
						(arc
							(start 0.1778 0.2794)
							(mid 0.249642 0.249642)
							(end 0.2794 0.1778)
						)
						(arc
							(start 0.2794 -0.1778)
							(mid 0.249642 -0.249642)
							(end 0.1778 -0.2794)
						)
					)
					(width 0)
					(fill yes)
				)
			)
		)
		(pad "2" smd custom
			(at 0 0.4445 90)
			(size 0.1397 0.1397)
			(layers "F.Cu" "F.Mask" "F.Paste")
			(net "I2C_DRIVE_B_FLT_LED_SCL")
			(options
				(clearance outline)
				(anchor circle)
			)
			(primitives
				(gr_poly
					(pts
						(arc
							(start -0.1778 -0.2794)
							(mid -0.249642 -0.249642)
							(end -0.2794 -0.1778)
						)
						(arc
							(start -0.2794 0.1778)
							(mid -0.249642 0.249642)
							(end -0.1778 0.2794)
						)
						(arc
							(start 0.1778 0.2794)
							(mid 0.249642 0.249642)
							(end 0.2794 0.1778)
						)
						(arc
							(start 0.2794 -0.1778)
							(mid 0.249642 -0.249642)
							(end 0.1778 -0.2794)
						)
					)
					(width 0)
					(fill yes)
				)
			)
		)
	)
	(footprint ""
		(layer "F.Cu")
		(at 363.1184 -135.6106 -90)
		(property "Reference" "C285"
			(at 0 0 270)
			(layer "F.SilkS")
			(hide yes)
			(effects
				(font
					(size 1.27 1.27)
				)
			)
		)
		(property "Value" "SCD033U25V2KX-GP"
			(at 1.1811 -2.7051 270)
			(unlocked yes)
			(layer "F.Fab")
			(hide yes)
			(effects
				(font
					(size 1.016 1.016)
					(thickness 0.1524)
				)
			)
		)
		(property "Device Type" "C402H22"
			(at 1.1811 -4.2291 270)
			(unlocked yes)
			(layer "F.Fab")
			(hide yes)
			(effects
				(font
					(size 1.016 1.016)
					(thickness 0.1524)
				)
			)
		)
		(duplicate_pad_numbers_are_jumpers no)
		(fp_rect
			(start -0.4318 0.9525)
			(end 0.4318 -0.9525)
			(stroke
				(width 0)
				(type default)
			)
			(fill no)
			(layer "F.CrtYd")
		)
		(fp_rect
			(start -0.4318 0.9525)
			(end 0.4318 -0.9525)
			(stroke
				(width 0)
				(type default)
			)
			(fill no)
			(layer "F.Fab")
		)
		(pad "1" smd custom
			(at 0 -0.4445 270)
			(size 0.1524 0.1524)
			(layers "F.Cu" "F.Mask" "F.Paste")
			(net "SW_HDD_P19")
			(options
				(clearance outline)
				(anchor circle)
			)
			(primitives
				(gr_poly
					(pts
						(arc
							(start 0.3048 -0.2032)
							(mid 0.275042 -0.275042)
							(end 0.2032 -0.3048)
						)
						(arc
							(start -0.2032 -0.3048)
							(mid -0.275042 -0.275042)
							(end -0.3048 -0.2032)
						)
						(arc
							(start -0.3048 0.2032)
							(mid -0.275042 0.275042)
							(end -0.2032 0.3048)
						)
						(arc
							(start 0.2032 0.3048)
							(mid 0.275042 0.275042)
							(end 0.3048 0.2032)
						)
					)
					(width 0)
					(fill yes)
				)
			)
		)
		(pad "2" smd custom
			(at 0 0.4445 270)
			(size 0.1524 0.1524)
			(layers "F.Cu" "F.Mask" "F.Paste")
			(net "GND")
			(options
				(clearance outline)
				(anchor circle)
			)
			(primitives
				(gr_poly
					(pts
						(arc
							(start 0.3048 -0.2032)
							(mid 0.275042 -0.275042)
							(end 0.2032 -0.3048)
						)
						(arc
							(start -0.2032 -0.3048)
							(mid -0.275042 -0.275042)
							(end -0.3048 -0.2032)
						)
						(arc
							(start -0.3048 0.2032)
							(mid -0.275042 0.275042)
							(end -0.2032 0.3048)
						)
						(arc
							(start 0.2032 0.3048)
							(mid 0.275042 0.275042)
							(end 0.3048 0.2032)
						)
					)
					(width 0)
					(fill yes)
				)
			)
		)
	)
	(footprint ""
		(layer "F.Cu")
		(at 313.8424 -327.858882)
		(property "Reference" "R103"
			(at 0 0 0)
			(layer "F.SilkS")
			(hide yes)
			(effects
				(font
					(size 1.27 1.27)
				)
			)
		)
		(property "Value" "100KR2F-L1-GP"
			(at 0.064008 -3.993896 0)
			(unlocked yes)
			(layer "F.Fab")
			(hide yes)
			(effects
				(font
					(size 1.016 1.016)
					(thickness 0.1524)
				)
			)
		)
		(property "Device Type" "R402H16"
			(at 0.064008 -5.517896 0)
			(unlocked yes)
			(layer "F.Fab")
			(hide yes)
			(effects
				(font
					(size 1.016 1.016)
					(thickness 0.1524)
				)
			)
		)
		(duplicate_pad_numbers_are_jumpers no)
		(fp_line
			(start -0.508 -0.9398)
			(end -0.508 0.9398)
			(stroke
				(width 0.1524)
				(type default)
			)
			(layer "F.SilkS")
		)
		(fp_line
			(start 0.508 -0.9398)
			(end -0.508 -0.9398)
			(stroke
				(width 0.1524)
				(type default)
			)
			(layer "F.SilkS")
		)
		(fp_rect
			(start -0.508 0.9398)
			(end 0.508 -0.9398)
			(stroke
				(width 0)
				(type default)
			)
			(fill no)
			(layer "F.CrtYd")
		)
		(fp_rect
			(start -0.508 0.9398)
			(end 0.508 -0.9398)
			(stroke
				(width 0)
				(type default)
			)
			(fill no)
			(layer "F.Fab")
		)
		(pad "1" smd custom
			(at 0 -0.4445)
			(size 0.1397 0.1397)
			(layers "F.Cu" "F.Mask" "F.Paste")
			(net "PWM_BMC_B_ZONE_D")
			(options
				(clearance outline)
				(anchor circle)
			)
			(primitives
				(gr_poly
					(pts
						(arc
							(start -0.1778 -0.2794)
							(mid -0.249642 -0.249642)
							(end -0.2794 -0.1778)
						)
						(arc
							(start -0.2794 0.1778)
							(mid -0.249642 0.249642)
							(end -0.1778 0.2794)
						)
						(arc
							(start 0.1778 0.2794)
							(mid 0.249642 0.249642)
							(end 0.2794 0.1778)
						)
						(arc
							(start 0.2794 -0.1778)
							(mid 0.249642 -0.249642)
							(end 0.1778 -0.2794)
						)
					)
					(width 0)
					(fill yes)
				)
			)
		)
		(pad "2" smd custom
			(at 0 0.4445)
			(size 0.1397 0.1397)
			(layers "F.Cu" "F.Mask" "F.Paste")
			(net "GND")
			(options
				(clearance outline)
				(anchor circle)
			)
			(primitives
				(gr_poly
					(pts
						(arc
							(start -0.1778 -0.2794)
							(mid -0.249642 -0.249642)
							(end -0.2794 -0.1778)
						)
						(arc
							(start -0.2794 0.1778)
							(mid -0.249642 0.249642)
							(end -0.1778 0.2794)
						)
						(arc
							(start 0.1778 0.2794)
							(mid 0.249642 0.249642)
							(end 0.2794 0.1778)
						)
						(arc
							(start 0.2794 -0.1778)
							(mid 0.249642 -0.249642)
							(end 0.1778 -0.2794)
						)
					)
					(width 0)
					(fill yes)
				)
			)
		)
	)
)
